(kicad_pcb
	(version 20241229)
	(generator "pcbnew")
	(generator_version "9.0")
	(general
		(thickness 1.61)
		(legacy_teardrops no)
	)
	(paper "A3")
	(title_block
		(title "SO-DIMM DDR5 Tester")
		(date "2025-11-26")
		(rev "1.3.0")
		(comment 9 "footprints 208-212 of 627")
	)
	(layers
		(0 "F.Cu" signal)
		(4 "In1.Cu" power)
		(6 "In2.Cu" mixed)
		(8 "In3.Cu" power)
		(10 "In4.Cu" mixed)
		(12 "In5.Cu" power)
		(14 "In6.Cu" mixed)
		(16 "In7.Cu" power)
		(18 "In8.Cu" power)
		(20 "In9.Cu" mixed)
		(22 "In10.Cu" power)
		(2 "B.Cu" signal)
		(9 "F.Adhes" user "F.Adhesive")
		(11 "B.Adhes" user "B.Adhesive")
		(13 "F.Paste" user)
		(15 "B.Paste" user)
		(5 "F.SilkS" user "F.Silkscreen")
		(7 "B.SilkS" user "B.Silkscreen")
		(1 "F.Mask" user)
		(3 "B.Mask" user)
		(17 "Dwgs.User" user "User.Drawings")
		(19 "Cmts.User" user "User.Comments")
		(21 "Eco1.User" user "User.Eco1")
		(23 "Eco2.User" user "User.Eco2")
		(25 "Edge.Cuts" user)
		(27 "Margin" user)
		(31 "F.CrtYd" user "F.Courtyard")
		(29 "B.CrtYd" user "B.Courtyard")
		(35 "F.Fab" user)
		(33 "B.Fab" user)
	)
	(footprint "antmicro-footprints:VSSOP-8_2.3x2mm_P0.5mm"
		(layer "F.Cu")
		(at 181.65 194.3)
		(property "Reference" "U24"
			(at -1.15 2.1 0)
			(layer "F.SilkS")
			(effects
				(font
					(size 0.7 0.7)
					(thickness 0.15)
				)
				(justify left bottom)
			)
		)
		(property "Value" "TS5A3359_VSSOP"
			(at 0 2.258 0)
			(layer "F.Fab")
			(effects
				(font
					(size 0.7 0.7)
					(thickness 0.15)
				)
				(justify left bottom)
			)
		)
		(property "Datasheet" "https://www.ti.com/general/docs/suppproductinfo.tsp?distId=26&gotoUrl=http%3A%2F%2Fwww.ti.com%2Flit%2Fgpn%2Fts5a3359"
			(at 0 0 0)
			(layer "F.Fab")
			(hide yes)
			(effects
				(font
					(size 1.27 1.27)
					(thickness 0.15)
				)
			)
		)
		(property "Author" "Antmicro"
			(at 0 0 0)
			(layer "F.Fab")
			(hide yes)
			(effects
				(font
					(size 1 1)
					(thickness 0.15)
				)
			)
		)
		(property "License" "Apache-2.0"
			(at 0 0 0)
			(layer "F.Fab")
			(hide yes)
			(effects
				(font
					(size 1 1)
					(thickness 0.15)
				)
			)
		)
		(property "MPN" "TS5A3359DCUR"
			(at 0 0 0)
			(layer "F.Fab")
			(hide yes)
			(effects
				(font
					(size 1 1)
					(thickness 0.15)
				)
			)
		)
		(property "Manufacturer" "Texas Instruments"
			(at 0 0 0)
			(layer "F.Fab")
			(hide yes)
			(effects
				(font
					(size 1 1)
					(thickness 0.15)
				)
			)
		)
		(sheetname "/I^{2}C/")
		(sheetfile "i2c.kicad_sch")
		(attr smd)
		(fp_line
			(start -0.82 -0.992)
			(end 0.825 -0.992)
			(stroke
				(width 0.15)
				(type solid)
			)
			(layer "F.SilkS")
		)
		(fp_line
			(start 0.825 1.007)
			(end -0.82 1.007)
			(stroke
				(width 0.15)
				(type solid)
			)
			(layer "F.SilkS")
		)
		(fp_circle
			(center -1.402 -1.192)
			(end -1.352 -1.192)
			(stroke
				(width 0.15)
				(type solid)
			)
			(fill yes)
			(layer "F.SilkS")
		)
		(fp_rect
			(start 1.8 1.35)
			(end -1.8 -1.35)
			(stroke
				(width 0.05)
				(type solid)
			)
			(fill no)
			(layer "F.CrtYd")
		)
		(fp_line
			(start -0.7 -0.99)
			(end -1.14 -0.55)
			(stroke
				(width 0.15)
				(type solid)
			)
			(layer "F.Fab")
		)
		(fp_rect
			(start -1.147 -0.992)
			(end 1.151 1.007)
			(stroke
				(width 0.15)
				(type solid)
			)
			(fill no)
			(layer "F.Fab")
		)
		(pad "1" smd rect
			(at -1.372 -0.742)
			(size 0.75 0.4)
			(layers "F.Cu" "F.Mask" "F.Paste")
			(net 682 "/FPGA bank 14/FPGA_DDR.SCL")
			(pinfunction "NO1")
			(pintype "passive")
		)
		(pad "2" smd rect
			(at -1.372 -0.244)
			(size 0.75 0.3)
			(layers "F.Cu" "F.Mask" "F.Paste")
			(net 689 "/FPGA bank 14/FPGA_PWR.SCL")
			(pinfunction "NO2")
			(pintype "passive")
		)
		(pad "3" smd rect
			(at -1.372 0.256)
			(size 0.75 0.3)
			(layers "F.Cu" "F.Mask" "F.Paste")
			(net 671 "/Debug FTDI/FTDI.SCL")
			(pinfunction "NO3")
			(pintype "passive")
		)
		(pad "4" smd rect
			(at -1.372 0.757)
			(size 0.75 0.4)
			(layers "F.Cu" "F.Mask" "F.Paste")
			(net 1 "GND")
			(pinfunction "GND")
			(pintype "passive")
		)
		(pad "5" smd rect
			(at 1.377 0.757)
			(size 0.75 0.4)
			(layers "F.Cu" "F.Mask" "F.Paste")
			(net 687 "IN2")
			(pinfunction "IN2")
			(pintype "passive")
		)
		(pad "6" smd rect
			(at 1.377 0.256)
			(size 0.75 0.3)
			(layers "F.Cu" "F.Mask" "F.Paste")
			(net 686 "IN1")
			(pinfunction "IN1")
			(pintype "passive")
		)
		(pad "7" smd rect
			(at 1.377 -0.244)
			(size 0.75 0.3)
			(layers "F.Cu" "F.Mask" "F.Paste")
			(net 691 "/I^{2}C/PWR.SCL")
			(pinfunction "COM")
			(pintype "passive")
		)
		(pad "8" smd rect
			(at 1.377 -0.742)
			(size 0.75 0.4)
			(layers "F.Cu" "F.Mask" "F.Paste")
			(net 41 "+3V3_AON")
			(pinfunction "VCC")
			(pintype "passive")
		)
	)
	(footprint "antmicro-footprints:R_0402_1005Metric"
		(layer "F.Cu")
		(at 115.45 186.6 -90)
		(descr "Resistor SMD 0402")
		(tags "resistor SMD 0402")
		(property "Reference" "R9"
			(at -1.122484 -0.772697 270)
			(layer "F.SilkS")
			(hide yes)
			(effects
				(font
					(size 0.7 0.7)
					(thickness 0.15)
				)
				(justify left bottom)
			)
		)
		(property "Value" "R_22R_0402"
			(at -1.011843 1.772047 270)
			(layer "F.Fab")
			(effects
				(font
					(size 0.7 0.7)
					(thickness 0.15)
				)
				(justify left bottom)
			)
		)
		(property "Datasheet" "https://www.bourns.com/docs/product-datasheets/cr.pdf"
			(at 0 0 270)
			(layer "F.Fab")
			(hide yes)
			(effects
				(font
					(size 1.27 1.27)
					(thickness 0.15)
				)
			)
		)
		(property "Author" "Antmicro"
			(at -71.15 302.05 0)
			(layer "F.Fab")
			(hide yes)
			(effects
				(font
					(size 1 1)
					(thickness 0.15)
				)
			)
		)
		(property "License" "Apache-2.0"
			(at -71.15 302.05 0)
			(layer "F.Fab")
			(hide yes)
			(effects
				(font
					(size 1 1)
					(thickness 0.15)
				)
			)
		)
		(property "MPN" "CR0402-FX-22R0GLF"
			(at -71.15 302.05 0)
			(layer "F.Fab")
			(hide yes)
			(effects
				(font
					(size 1 1)
					(thickness 0.15)
				)
			)
		)
		(property "Manufacturer" "Bourns"
			(at -71.15 302.05 0)
			(layer "F.Fab")
			(hide yes)
			(effects
				(font
					(size 1 1)
					(thickness 0.15)
				)
			)
		)
		(property "Tolerance" "1%"
			(at -71.15 302.05 0)
			(layer "F.Fab")
			(hide yes)
			(effects
				(font
					(size 1 1)
					(thickness 0.15)
				)
			)
		)
		(property "Val" "22R"
			(at -71.15 302.05 0)
			(layer "F.Fab")
			(hide yes)
			(effects
				(font
					(size 1 1)
					(thickness 0.15)
				)
			)
		)
		(sheetname "/HyperRAM + QSPI Flash/")
		(sheetfile "hyperram-flash.kicad_sch")
		(attr smd)
		(fp_rect
			(start -0.93 -0.47)
			(end 0.93 0.47)
			(stroke
				(width 0.05)
				(type solid)
			)
			(fill no)
			(layer "F.CrtYd")
		)
		(fp_rect
			(start -0.5 -0.25)
			(end 0.5 0.25)
			(stroke
				(width 0.15)
				(type solid)
			)
			(fill no)
			(layer "F.Fab")
		)
		(pad "1" smd roundrect
			(at -0.485 0 270)
			(size 0.59 0.64)
			(layers "F.Cu" "F.Mask" "F.Paste")
			(roundrect_rratio 0.25)
			(net 360 "/HyperRAM + QSPI Flash/IO3")
			(pintype "passive")
		)
		(pad "2" smd roundrect
			(at 0.485 0 270)
			(size 0.59 0.64)
			(layers "F.Cu" "F.Mask" "F.Paste")
			(roundrect_rratio 0.25)
			(net 629 "/FPGA Config/FLASH.IO3")
			(pintype "passive")
		)
	)
	(footprint "antmicro-footprints:NetTie-2_SMD_Pad0.127mm"
		(layer "F.Cu")
		(at 187.8305 162.002 180)
		(descr "Net tie, 2 pin, 0.127mm  SMD pads")
		(tags "net tie")
		(property "Reference" "NT14"
			(at -0.128 -1.345 180)
			(layer "F.SilkS")
			(hide yes)
			(effects
				(font
					(size 0.7 0.7)
					(thickness 0.15)
				)
				(justify left bottom)
			)
		)
		(property "Value" "Net-Tie_P0.127mm"
			(at 0 1.199 180)
			(layer "F.Fab")
			(effects
				(font
					(size 0.7 0.7)
					(thickness 0.15)
				)
				(justify left bottom)
			)
		)
		(property "Author" "Antmicro"
			(at 375.661 324.004 0)
			(layer "F.Fab")
			(hide yes)
			(effects
				(font
					(size 1 1)
					(thickness 0.15)
				)
			)
		)
		(property "License" "Apache-2.0"
			(at 375.661 324.004 0)
			(layer "F.Fab")
			(hide yes)
			(effects
				(font
					(size 1 1)
					(thickness 0.15)
				)
			)
		)
		(property "MPN" ""
			(at 375.661 324.004 0)
			(layer "F.Fab")
			(hide yes)
			(effects
				(font
					(size 1 1)
					(thickness 0.15)
				)
			)
		)
		(property "Manufacturer" ""
			(at 375.661 324.004 0)
			(layer "F.Fab")
			(hide yes)
			(effects
				(font
					(size 1 1)
					(thickness 0.15)
				)
			)
		)
		(property ki_fp_filters "Net*Tie*")
		(sheetname "/Supply/")
		(sheetfile "supply.kicad_sch")
		(attr smd exclude_from_pos_files exclude_from_bom)
		(net_tie_pad_groups "1, 2")
		(fp_poly
			(pts
				(xy -0.0635 -0.0635) (xy 0.0625 -0.0635) (xy 0.0625 0.0635) (xy -0.0635 0.0635)
			)
			(stroke
				(width 0)
				(type solid)
			)
			(fill yes)
			(layer "F.Cu")
		)
		(pad "1" smd roundrect
			(at -0.127 0)
			(size 0.127 0.127)
			(layers "F.Cu")
			(roundrect_rratio 0.5)
			(chamfer_ratio 0)
			(chamfer top_left bottom_left)
			(net 146 "/Supply/5V_SEN_-")
			(pinfunction "1")
			(pintype "passive")
		)
		(pad "2" smd roundrect
			(at 0.126 0 180)
			(size 0.127 0.127)
			(layers "F.Cu")
			(roundrect_rratio 0.5)
			(chamfer_ratio 0)
			(chamfer top_left bottom_left)
			(net 201 "+5V")
			(pinfunction "2")
			(pintype "passive")
		)
	)
	(footprint "antmicro-footprints:R_0402_1005Metric"
		(layer "F.Cu")
		(at 106.25 184.8 -90)
		(descr "Resistor SMD 0402")
		(tags "resistor SMD 0402")
		(property "Reference" "R92"
			(at -1.122484 -0.772697 270)
			(layer "F.SilkS")
			(hide yes)
			(effects
				(font
					(size 0.7 0.7)
					(thickness 0.15)
				)
				(justify left bottom)
			)
		)
		(property "Value" "R_0R_0402"
			(at -1.011843 1.772047 270)
			(layer "F.Fab")
			(effects
				(font
					(size 0.7 0.7)
					(thickness 0.15)
				)
				(justify left bottom)
			)
		)
		(property "Datasheet" "https://industrial.panasonic.com/cdbs/www-data/pdf/RDA0000/AOA0000C301.pdf"
			(at 0 0 270)
			(layer "F.Fab")
			(hide yes)
			(effects
				(font
					(size 1.27 1.27)
					(thickness 0.15)
				)
			)
		)
		(property "Author" "Antmicro"
			(at -78.55 291.05 0)
			(layer "F.Fab")
			(hide yes)
			(effects
				(font
					(size 1 1)
					(thickness 0.15)
				)
			)
		)
		(property "Current" "1A"
			(at -78.55 291.05 0)
			(layer "F.Fab")
			(hide yes)
			(effects
				(font
					(size 1 1)
					(thickness 0.15)
				)
			)
		)
		(property "License" "Apache-2.0"
			(at -78.55 291.05 0)
			(layer "F.Fab")
			(hide yes)
			(effects
				(font
					(size 1 1)
					(thickness 0.15)
				)
			)
		)
		(property "MPN" "ERJ2GE0R00X"
			(at -78.55 291.05 0)
			(layer "F.Fab")
			(hide yes)
			(effects
				(font
					(size 1 1)
					(thickness 0.15)
				)
			)
		)
		(property "Manufacturer" "Panasonic"
			(at -78.55 291.05 0)
			(layer "F.Fab")
			(hide yes)
			(effects
				(font
					(size 1 1)
					(thickness 0.15)
				)
			)
		)
		(property "Tolerance" ""
			(at -78.55 291.05 0)
			(layer "F.Fab")
			(hide yes)
			(effects
				(font
					(size 1 1)
					(thickness 0.15)
				)
			)
		)
		(property "Val" "0R"
			(at -78.55 291.05 0)
			(layer "F.Fab")
			(hide yes)
			(effects
				(font
					(size 1 1)
					(thickness 0.15)
				)
			)
		)
		(sheetname "/Debug FTDI/")
		(sheetfile "debug-ftdi.kicad_sch")
		(attr smd)
		(fp_rect
			(start -0.93 -0.47)
			(end 0.93 0.47)
			(stroke
				(width 0.05)
				(type solid)
			)
			(fill no)
			(layer "F.CrtYd")
		)
		(fp_rect
			(start -0.5 -0.25)
			(end 0.5 0.25)
			(stroke
				(width 0.15)
				(type solid)
			)
			(fill no)
			(layer "F.Fab")
		)
		(pad "1" smd roundrect
			(at -0.485 0 270)
			(size 0.59 0.64)
			(layers "F.Cu" "F.Mask" "F.Paste")
			(roundrect_rratio 0.25)
			(net 670 "/Debug FTDI/FTDI_SCL")
			(pintype "passive")
		)
		(pad "2" smd roundrect
			(at 0.485 0 270)
			(size 0.59 0.64)
			(layers "F.Cu" "F.Mask" "F.Paste")
			(roundrect_rratio 0.25)
			(net 671 "/Debug FTDI/FTDI.SCL")
			(pintype "passive")
		)
	)
	(footprint "antmicro-footprints:LED_0603_1608Metric_G"
		(layer "F.Cu")
		(at 89.050501 116.426 -90)
		(descr "LED SMD 0603 Green")
		(tags "LED SMD 0603 Green")
		(property "Reference" "D5"
			(at -0.001 -0.901 270)
			(layer "F.SilkS")
			(hide yes)
			(effects
				(font
					(size 0.7 0.7)
					(thickness 0.15)
				)
				(justify left bottom)
			)
		)
		(property "Value" "LED_G_0603_KP-1608CGCK"
			(at -0.001 1.599 270)
			(layer "F.Fab")
			(effects
				(font
					(size 0.7 0.7)
					(thickness 0.15)
				)
				(justify left bottom)
			)
		)
		(property "Datasheet" "http://www.farnell.com/datasheets/2045956.pdf"
			(at 0 0 270)
			(layer "F.Fab")
			(hide yes)
			(effects
				(font
					(size 1.27 1.27)
					(thickness 0.15)
				)
			)
		)
		(property "Author" "Antmicro"
			(at -27.375499 205.476501 0)
			(layer "F.Fab")
			(hide yes)
			(effects
				(font
					(size 1 1)
					(thickness 0.15)
				)
			)
		)
		(property "License" "Apache-2.0"
			(at -27.375499 205.476501 0)
			(layer "F.Fab")
			(hide yes)
			(effects
				(font
					(size 1 1)
					(thickness 0.15)
				)
			)
		)
		(property "MPN" "KP-1608CGCK"
			(at -27.375499 205.476501 0)
			(layer "F.Fab")
			(hide yes)
			(effects
				(font
					(size 1 1)
					(thickness 0.15)
				)
			)
		)
		(property "Manufacturer" "Kingbright"
			(at -27.375499 205.476501 0)
			(layer "F.Fab")
			(hide yes)
			(effects
				(font
					(size 1 1)
					(thickness 0.15)
				)
			)
		)
		(sheetname "/FPGA bank 14/")
		(sheetfile "fpga-bank-14.kicad_sch")
		(attr smd)
		(fp_line
			(start -0.271 0.348)
			(end 0.269 0.348)
			(stroke
				(width 0.15)
				(type solid)
			)
			(layer "F.SilkS")
		)
		(fp_line
			(start 1.249 0.319)
			(end 1.249 -0.321)
			(stroke
				(width 0.15)
				(type solid)
			)
			(layer "F.SilkS")
		)
		(fp_line
			(start -0.107 -0.001)
			(end -0.291 -0.001)
			(stroke
				(width 0.1)
				(type solid)
			)
			(layer "F.SilkS")
		)
		(fp_line
			(start 0.092 -0.001)
			(end -0.107 0.198)
			(stroke
				(width 0.1)
				(type solid)
			)
			(layer "F.SilkS")
		)
		(fp_line
			(start 0.092 -0.001)
			(end 0.292 -0.001)
			(stroke
				(width 0.1)
				(type solid)
			)
			(layer "F.SilkS")
		)
		(fp_line
			(start -0.107 -0.201)
			(end -0.107 0.198)
			(stroke
				(width 0.1)
				(type solid)
			)
			(layer "F.SilkS")
		)
		(fp_line
			(start -0.107 -0.201)
			(end 0.092 -0.001)
			(stroke
				(width 0.1)
				(type solid)
			)
			(layer "F.SilkS")
		)
		(fp_line
			(start 0.092 -0.201)
			(end 0.092 0.198)
			(stroke
				(width 0.1)
				(type solid)
			)
			(layer "F.SilkS")
		)
		(fp_line
			(start -0.271 -0.349)
			(end 0.269 -0.349)
			(stroke
				(width 0.15)
				(type solid)
			)
			(layer "F.SilkS")
		)
		(fp_rect
			(start -1.2192 -0.6096)
			(end 1.27 0.6016)
			(stroke
				(width 0.05)
				(type solid)
			)
			(fill no)
			(layer "F.CrtYd")
		)
		(fp_line
			(start -0.202 0.201)
			(end 0.1 -0.001)
			(stroke
				(width 0.15)
				(type solid)
			)
			(layer "F.Fab")
		)
		(fp_line
			(start 0.198 0.201)
			(end 0.198 -0.101)
			(stroke
				(width 0.15)
				(type solid)
			)
			(layer "F.Fab")
		)
		(fp_line
			(start -0.849 0.025)
			(end -0.442 0.381)
			(stroke
				(width 0.15)
				(type solid)
			)
			(layer "F.Fab")
		)
		(fp_line
			(start -0.6 -0.001)
			(end -0.202 -0.001)
			(stroke
				(width 0.15)
				(type solid)
			)
			(layer "F.Fab")
		)
		(fp_line
			(start -0.202 -0.001)
			(end -0.202 0.201)
			(stroke
				(width 0.15)
				(type solid)
			)
			(layer "F.Fab")
		)
		(fp_line
			(start 0.1 -0.001)
			(end -0.202 -0.201)
			(stroke
				(width 0.15)
				(type solid)
			)
			(layer "F.Fab")
		)
		(fp_line
			(start 0.198 -0.001)
			(end 0.596 -0.001)
			(stroke
				(width 0.15)
				(type solid)
			)
			(layer "F.Fab")
		)
		(fp_line
			(start -0.202 -0.201)
			(end -0.202 -0.001)
			(stroke
				(width 0.15)
				(type solid)
			)
			(layer "F.Fab")
		)
		(fp_line
			(start 0.198 -0.201)
			(end 0.198 -0.101)
			(stroke
				(width 0.15)
				(type solid)
			)
			(layer "F.Fab")
		)
		(fp_rect
			(start -0.849 -0.401)
			(end 0.849 0.401)
			(stroke
				(width 0.15)
				(type solid)
			)
			(fill no)
			(layer "F.Fab")
		)
		(pad "1" smd rect
			(at -0.751 -0.001 90)
			(size 0.8 0.8)
			(layers "F.Cu" "F.Mask" "F.Paste")
			(net 200 "+3V3")
			(pinfunction "1")
			(pintype "passive")
		)
		(pad "2" smd rect
			(at 0.749 -0.001 90)
			(size 0.8 0.8)
			(layers "F.Cu" "F.Mask" "F.Paste")
			(net 308 "Net-(D5-Pad2)")
			(pinfunction "2")
			(pintype "passive")
		)
	)
)
